FILE_TYPE = CONNECTIVITY;
{Allegro Design Entry HDL 17.2-2016 S081 (4005846) 1/11/2022}
"PAGE_NUMBER" = 110;
0"NC";
1"P3V3_AUX\g";
2"P12V_S3_AUX_CPU1_NVDIMM\g";
3"P12V_S3_AUX_CPU1_NVDIMM\g";
4"P3V3_AUX\g";
5"GND\g";
6"GND\g";
7"GND\g";
8"GND\g";
9"GND\g";
10"M_G_CPU1_SA_DQ<31:0>";
11"M_G_CPU1_SA_CB<7:0>";
12"M_G_CPU1_SB_CB<7:0>";
13"M_G_CPU1_SA_CA<6:0>";
14"M_G_CPU1_SB_CA<6:0>";
15"M_G_CPU1_SB_DQ<31:0>";
16"M_G_CPU1_SB_DQS_DP<9:0>";
17"M_G_CPU1_SA_DQS_DP<9:0>";
18"M_G_CPU1_SB_DQS_DN<9:0>";
19"M_G_CPU1_SA_DQS_DN<9:0>";
20"I3C_SPD_DDREFGH_CPU1_LVC1_SDA";
21"PD_CHG_CPU1_DIMM1_SAA";
22"M_G_CPU1_ALERT_N";
23"RST_M_GH_CPU1_FPGA_N";
24"I3C_SPD_DDREFGH_CPU1_LVC1_SCL_R5";
25"I3C_SPD_DDREFGH_CPU1_LVC1_SCL";
26"PWRGD_CHG_CPU1_DIMM1";
27"TP_CHG_CPU1_DIMM1_FRU_6";
28"M_G_CPU1_SB_CB<3>";
29"M_G_CPU1_SB_DQS_DN<5>";
30"M_G_CPU1_SA_DQS_DN<9>";
31"M_G_CPU1_SA_DQS_DN<6>";
32"M_G_CPU1_SA_DQS_DN<8>";
33"M_G_CPU1_SA_DQS_DN<7>";
34"M_G_CPU1_SA_DQS_DN<5>";
35"M_G_CPU1_SA_DQS_DN<4>";
36"M_G_CPU1_SA_DQS_DN<3>";
37"M_G_CPU1_SA_DQS_DN<2>";
38"M_G_CPU1_SA_DQS_DN<1>";
39"M_G_CPU1_SB_DQS_DN<9>";
40"M_G_CPU1_SA_DQS_DN<0>";
41"M_G_CPU1_SB_DQS_DN<8>";
42"M_G_CPU1_SB_DQS_DN<7>";
43"M_G_CPU1_SB_DQS_DN<6>";
44"M_G_CPU1_SB_DQS_DN<4>";
45"M_G_CPU1_SB_DQS_DN<1>";
46"M_G_CPU1_SB_DQS_DN<3>";
47"M_G_CPU1_SB_DQS_DN<2>";
48"M_G_CPU1_SB_DQS_DN<0>";
49"M_G_CPU1_SA_DQS_DP<6>";
50"M_G_CPU1_SA_DQS_DP<7>";
51"M_G_CPU1_SA_DQS_DP<8>";
52"M_G_CPU1_SA_DQS_DP<9>";
53"M_G_CPU1_SA_DQS_DP<1>";
54"M_G_CPU1_SA_DQS_DP<2>";
55"M_G_CPU1_SA_DQS_DP<3>";
56"M_G_CPU1_SA_DQS_DP<4>";
57"M_G_CPU1_SA_DQS_DP<5>";
58"M_G_CPU1_SA_DQS_DP<0>";
59"M_G_CPU1_SB_DQS_DP<6>";
60"M_G_CPU1_SB_DQS_DP<7>";
61"M_G_CPU1_SB_DQS_DP<8>";
62"M_G_CPU1_SB_DQS_DP<9>";
63"M_G_CPU1_SB_DQS_DP<1>";
64"M_G_CPU1_SB_DQS_DP<2>";
65"M_G_CPU1_SB_DQS_DP<4>";
66"M_G_CPU1_SB_DQS_DP<3>";
67"M_G_CPU1_SB_DQS_DP<5>";
68"M_G_CPU1_SB_DQS_DP<0>";
69"M_G_CPU1_SB_CB<6>";
70"TP_CHG_CPU1_DIMM1_FRU_1";
71"TP_CHG_CPU1_DIMM1_FRU_4";
72"TP_CHG_CPU1_DIMM1_FRU_5";
73"M_G_CPU1_SA_CS_N<0>";
74"M_G_CPU1_SA_DQ<10>";
75"M_G_CPU1_SB_DQ<25>";
76"TP_CHG_CPU1_DIMM1_FRU_0";
77"TP_CHG_CPU1_DIMM1_FRU_2";
78"TP_CHG_CPU1_DIMM1_FRU_3";
79"M_G_CPU1_SB_PAR";
80"M_G_CPU1_SA_PAR";
81"M_G_CPU1_SB_RSP<0>";
82"M_G_CPU1_SA_RSP<0>";
83"M_G_CPU1_SB_DQ<0>";
84"M_G_CPU1_SB_DQ<1>";
85"M_G_CPU1_SB_DQ<2>";
86"M_G_CPU1_SB_DQ<3>";
87"M_G_CPU1_SB_DQ<4>";
88"M_G_CPU1_SB_DQ<5>";
89"M_G_CPU1_SB_DQ<6>";
90"M_G_CPU1_SB_DQ<7>";
91"M_G_CPU1_SB_DQ<8>";
92"M_G_CPU1_SB_DQ<9>";
93"M_G_CPU1_SB_DQ<10>";
94"M_G_CPU1_SB_DQ<11>";
95"M_G_CPU1_SB_DQ<12>";
96"M_G_CPU1_SB_DQ<13>";
97"M_G_CPU1_SB_DQ<14>";
98"M_G_CPU1_SB_DQ<15>";
99"M_G_CPU1_SB_DQ<16>";
100"M_G_CPU1_SB_DQ<17>";
101"M_G_CPU1_SB_DQ<18>";
102"M_G_CPU1_SB_DQ<19>";
103"M_G_CPU1_SB_DQ<20>";
104"M_G_CPU1_SB_DQ<21>";
105"M_G_CPU1_SB_DQ<22>";
106"M_G_CPU1_SB_DQ<23>";
107"M_G_CPU1_SB_DQ<24>";
108"M_G_CPU1_SB_DQ<26>";
109"M_G_CPU1_SB_DQ<27>";
110"M_G_CPU1_SB_DQ<28>";
111"M_G_CPU1_SB_DQ<29>";
112"M_G_CPU1_SB_DQ<30>";
113"M_G_CPU1_SB_DQ<31>";
114"M_G_CPU1_SA_DQ<0>";
115"M_G_CPU1_SA_DQ<1>";
116"M_G_CPU1_SA_DQ<2>";
117"M_G_CPU1_SA_DQ<3>";
118"M_G_CPU1_SA_DQ<4>";
119"M_G_CPU1_SA_DQ<5>";
120"M_G_CPU1_SA_DQ<6>";
121"M_G_CPU1_SA_DQ<7>";
122"M_G_CPU1_SA_DQ<8>";
123"M_G_CPU1_SA_DQ<9>";
124"M_G_CPU1_SA_DQ<11>";
125"M_G_CPU1_SA_DQ<12>";
126"M_G_CPU1_SA_DQ<13>";
127"M_G_CPU1_SA_DQ<14>";
128"M_G_CPU1_SA_DQ<15>";
129"M_G_CPU1_SA_DQ<16>";
130"M_G_CPU1_SA_DQ<17>";
131"M_G_CPU1_SA_DQ<18>";
132"M_G_CPU1_SA_DQ<19>";
133"M_G_CPU1_SA_DQ<20>";
134"M_G_CPU1_SA_DQ<21>";
135"M_G_CPU1_SA_DQ<22>";
136"M_G_CPU1_SA_DQ<23>";
137"M_G_CPU1_SA_DQ<24>";
138"M_G_CPU1_SA_DQ<25>";
139"M_G_CPU1_SA_DQ<26>";
140"M_G_CPU1_SA_DQ<27>";
141"M_G_CPU1_SA_DQ<28>";
142"M_G_CPU1_SA_DQ<29>";
143"M_G_CPU1_SA_DQ<30>";
144"M_G_CPU1_SB_CS_N<1>";
145"M_G_CPU1_SA_CS_N<1>";
146"M_G_CPU1_SB_CS_N<0>";
147"M_G_CPU1_CLK_DP<0>";
148"M_G_CPU1_CLK_DN<0>";
149"M_G_CPU1_SB_CB<0>";
150"M_G_CPU1_SB_CB<1>";
151"M_G_CPU1_SB_CB<2>";
152"M_G_CPU1_SB_CB<4>";
153"M_G_CPU1_SB_CB<5>";
154"M_G_CPU1_SA_CB<0>";
155"M_G_CPU1_SA_CB<2>";
156"M_G_CPU1_SA_CB<3>";
157"M_G_CPU1_SA_CB<5>";
158"M_G_CPU1_SA_CB<6>";
159"M_G_CPU1_SB_CA<6>";
160"M_G_CPU1_SA_CA<6>";
161"M_G_CPU1_SB_CA<5>";
162"M_G_CPU1_SA_CA<5>";
163"M_G_CPU1_SB_CA<4>";
164"M_G_CPU1_SA_CA<4>";
165"M_G_CPU1_SB_CA<3>";
166"M_G_CPU1_SA_CA<3>";
167"M_G_CPU1_SB_CA<2>";
168"M_G_CPU1_SA_CA<2>";
169"M_G_CPU1_SB_CA<1>";
170"M_G_CPU1_SA_CA<1>";
171"M_G_CPU1_SB_CA<0>";
172"M_G_CPU1_SA_CA<0>";
173"M_G_CPU1_SB_CB<7>";
174"M_G_CPU1_SA_CB<1>";
175"M_G_CPU1_SA_CB<4>";
176"M_G_CPU1_SA_CB<7>";
177"M_G_CPU1_SA_DQ<31>";
178"PD_CHG_CPU1_DIMM1_SAA";
%"UNIVERSAL_GND"
"1","(-2350,-425)","0","logical_power","I1";
;
HDL_POWER"GND"
CDS_LIB"logical_power";
"A"5;
%"TAP"
"1","(-925,3400)","0","standard","I100";
;
CDS_LIB"standard"
BODY_TYPE"PLUMBING"
HDL_TAP"TRUE";
"B \NAC \NWC"10;
"S \NAC"
BN"20"133;
%"TAP"
"1","(-925,3450)","0","standard","I101";
;
CDS_LIB"standard"
BODY_TYPE"PLUMBING"
HDL_TAP"TRUE";
"B \NAC \NWC"10;
"S \NAC"
BN"21"134;
%"TAP"
"1","(-925,3500)","0","standard","I102";
;
CDS_LIB"standard"
BODY_TYPE"PLUMBING"
HDL_TAP"TRUE";
"B \NAC \NWC"10;
"S \NAC"
BN"22"135;
%"TAP"
"1","(-925,3550)","0","standard","I103";
;
CDS_LIB"standard"
BODY_TYPE"PLUMBING"
HDL_TAP"TRUE";
"B \NAC \NWC"10;
"S \NAC"
BN"23"136;
%"TAP"
"1","(-925,3600)","0","standard","I104";
;
CDS_LIB"standard"
BODY_TYPE"PLUMBING"
HDL_TAP"TRUE";
"B \NAC \NWC"10;
"S \NAC"
BN"24"137;
%"TAP"
"1","(-925,3650)","0","standard","I105";
;
CDS_LIB"standard"
BODY_TYPE"PLUMBING"
HDL_TAP"TRUE";
"B \NAC \NWC"10;
"S \NAC"
BN"25"138;
%"TAP"
"1","(-2575,3700)","2","standard","I107";
;
CDS_LIB"standard"
BODY_TYPE"PLUMBING"
HDL_TAP"TRUE";
"B \NAC \NWC"13;
"S \NAC"
BN"1"170;
%"TAP"
"1","(-2575,3750)","2","standard","I108";
;
CDS_LIB"standard"
BODY_TYPE"PLUMBING"
HDL_TAP"TRUE";
"B \NAC \NWC"13;
"S \NAC"
BN"2"168;
%"TAP"
"1","(-2575,3800)","2","standard","I109";
;
CDS_LIB"standard"
BODY_TYPE"PLUMBING"
HDL_TAP"TRUE";
"B \NAC \NWC"13;
"S \NAC"
BN"3"166;
%"TAP"
"1","(-2575,3900)","2","standard","I110";
;
CDS_LIB"standard"
BODY_TYPE"PLUMBING"
HDL_TAP"TRUE";
"B \NAC \NWC"13;
"S \NAC"
BN"5"162;
%"TAP"
"1","(-2575,3850)","2","standard","I111";
;
CDS_LIB"standard"
BODY_TYPE"PLUMBING"
HDL_TAP"TRUE";
"B \NAC \NWC"13;
"S \NAC"
BN"4"164;
%"TAP"
"1","(-2575,3950)","2","standard","I112";
;
CDS_LIB"standard"
BODY_TYPE"PLUMBING"
HDL_TAP"TRUE";
"B \NAC \NWC"13;
"S \NAC"
BN"6"160;
%"TAP"
"1","(-925,3700)","0","standard","I113";
;
CDS_LIB"standard"
BODY_TYPE"PLUMBING"
HDL_TAP"TRUE";
"B \NAC \NWC"10;
"S \NAC"
BN"26"139;
%"TAP"
"1","(-925,3750)","0","standard","I114";
;
CDS_LIB"standard"
BODY_TYPE"PLUMBING"
HDL_TAP"TRUE";
"B \NAC \NWC"10;
"S \NAC"
BN"27"140;
%"TAP"
"1","(-925,3800)","0","standard","I115";
;
CDS_LIB"standard"
BODY_TYPE"PLUMBING"
HDL_TAP"TRUE";
"B \NAC \NWC"10;
"S \NAC"
BN"28"141;
%"TAP"
"1","(-925,3850)","0","standard","I116";
;
CDS_LIB"standard"
BODY_TYPE"PLUMBING"
HDL_TAP"TRUE";
"B \NAC \NWC"10;
"S \NAC"
BN"29"142;
%"TAP"
"1","(-925,3900)","0","standard","I117";
;
CDS_LIB"standard"
BODY_TYPE"PLUMBING"
HDL_TAP"TRUE";
"B \NAC \NWC"10;
"S \NAC"
BN"30"143;
%"TAP"
"1","(-925,3950)","0","standard","I118";
;
CDS_LIB"standard"
BODY_TYPE"PLUMBING"
HDL_TAP"TRUE";
"B \NAC \NWC"10;
"S \NAC"
BN"31"177;
%"UNIVERSAL_GND"
"1","(800,-300)","0","logical_power","I119";
;
HDL_POWER"GND"
CDS_LIB"logical_power";
"A"6;
%"Q_CAP"
"1","(800,75)","0","pure_quanta","I120";
;
PART_NUMBER"CH5221MEB00"
PACK_TYPE"C0402"
TOLERANCE"20%"
VALUE"2.2UF"
VOLTAGE"6.3V"
MATERIAL"X6S"
$LOCATION"C81"
CDS_LIB"pure_quanta"
$LOCATION"C81"
CDS_LOCATION"C81"
$SEC"1"
CDS_SEC"1";
"B"
$PN"2"6;
"A"
$PN"1"1;
%"VCC_CORE"
"1","(800,400)","0","logical_power","I121";
;
HDL_POWER"P3V3_AUX"
CDS_LIB"logical_power";
"A"1;
%"Q_CAP"
"1","(1800,75)","0","pure_quanta","I124";
;
PART_NUMBER"CH6103KEA00"
VALUE"10UF"
PACK_TYPE"C0805"
TOLERANCE"10%"
VOLTAGE"16V"
MATERIAL"X6S"
$LOCATION"C82"
CDS_LIB"pure_quanta"
$LOCATION"C82"
CDS_LOCATION"C82"
$SEC"1"
CDS_SEC"1";
"B"
$PN"2"7;
"A"
$PN"1"2;
%"VCC_CORE"
"1","(1800,400)","0","logical_power","I125";
;
HDL_POWER"P12V_S3_AUX_CPU1_NVDIMM"
CDS_LIB"logical_power";
"A"2;
%"Q_CAP"
"1","(2425,75)","0","pure_quanta","I126";
;
PART_NUMBER"CH6103KEA00"
TOLERANCE"10%"
PACK_TYPE"C0805"
VOLTAGE"16V"
VALUE"10UF"
MATERIAL"X6S"
$LOCATION"C83"
CDS_LIB"pure_quanta"
$LOCATION"C83"
CDS_LOCATION"C83"
$SEC"1"
CDS_SEC"1";
"B"
$PN"2"7;
"A"
$PN"1"2;
%"UNIVERSAL_GND"
"1","(2425,-300)","0","logical_power","I127";
;
HDL_POWER"GND"
CDS_LIB"logical_power";
"A"7;
%"UNIVERSAL_GND"
"1","(3500,250)","0","logical_power","I128";
;
HDL_POWER"GND"
CDS_LIB"logical_power";
"A"8;
%"TAP"
"1","(1825,2000)","0","standard","I129";
;
CDS_LIB"standard"
BODY_TYPE"PLUMBING"
HDL_TAP"TRUE";
"B \NAC \NWC"16;
"S \NAC"
BN"0"68;
%"TAP"
"1","(1825,2100)","0","standard","I130";
;
CDS_LIB"standard"
BODY_TYPE"PLUMBING"
HDL_TAP"TRUE";
"B \NAC \NWC"16;
"S \NAC"
BN"1"63;
%"TAP"
"1","(2000,1950)","0","standard","I131";
;
CDS_LIB"standard"
BODY_TYPE"PLUMBING"
HDL_TAP"TRUE";
"B \NAC \NWC"18;
"S \NAC"
BN"0"48;
%"TAP"
"1","(2000,2050)","0","standard","I132";
;
CDS_LIB"standard"
BODY_TYPE"PLUMBING"
HDL_TAP"TRUE";
"B \NAC \NWC"18;
"S \NAC"
BN"1"45;
%"TAP"
"1","(2000,2150)","0","standard","I133";
;
CDS_LIB"standard"
BODY_TYPE"PLUMBING"
HDL_TAP"TRUE";
"B \NAC \NWC"18;
"S \NAC"
BN"2"47;
%"TAP"
"1","(1825,2200)","0","standard","I134";
;
CDS_LIB"standard"
BODY_TYPE"PLUMBING"
HDL_TAP"TRUE";
"B \NAC \NWC"16;
"S \NAC"
BN"2"64;
%"TAP"
"1","(1825,2400)","0","standard","I135";
;
CDS_LIB"standard"
BODY_TYPE"PLUMBING"
HDL_TAP"TRUE";
"B \NAC \NWC"16;
"S \NAC"
BN"4"65;
%"TAP"
"1","(1825,2300)","0","standard","I136";
;
CDS_LIB"standard"
BODY_TYPE"PLUMBING"
HDL_TAP"TRUE";
"B \NAC \NWC"16;
"S \NAC"
BN"3"66;
%"TAP"
"1","(2000,2350)","0","standard","I137";
;
CDS_LIB"standard"
BODY_TYPE"PLUMBING"
HDL_TAP"TRUE";
"B \NAC \NWC"18;
"S \NAC"
BN"4"44;
%"TAP"
"1","(2000,2250)","0","standard","I138";
;
CDS_LIB"standard"
BODY_TYPE"PLUMBING"
HDL_TAP"TRUE";
"B \NAC \NWC"18;
"S \NAC"
BN"3"46;
%"TAP"
"1","(1825,2500)","0","standard","I139";
;
CDS_LIB"standard"
BODY_TYPE"PLUMBING"
HDL_TAP"TRUE";
"B \NAC \NWC"16;
"S \NAC"
BN"5"67;
%"TAP"
"1","(1825,2600)","0","standard","I140";
;
CDS_LIB"standard"
BODY_TYPE"PLUMBING"
HDL_TAP"TRUE";
"B \NAC \NWC"16;
"S \NAC"
BN"6"59;
%"TAP"
"1","(2000,2450)","0","standard","I141";
;
CDS_LIB"standard"
BODY_TYPE"PLUMBING"
HDL_TAP"TRUE";
"B \NAC \NWC"18;
"S \NAC"
BN"5"29;
%"TAP"
"1","(2000,2650)","0","standard","I142";
;
CDS_LIB"standard"
BODY_TYPE"PLUMBING"
HDL_TAP"TRUE";
"B \NAC \NWC"18;
"S \NAC"
BN"7"42;
%"TAP"
"1","(2000,2550)","0","standard","I143";
;
CDS_LIB"standard"
BODY_TYPE"PLUMBING"
HDL_TAP"TRUE";
"B \NAC \NWC"18;
"S \NAC"
BN"6"43;
%"TAP"
"1","(1825,2700)","0","standard","I144";
;
CDS_LIB"standard"
BODY_TYPE"PLUMBING"
HDL_TAP"TRUE";
"B \NAC \NWC"16;
"S \NAC"
BN"7"60;
%"TAP"
"1","(1825,2800)","0","standard","I145";
;
CDS_LIB"standard"
BODY_TYPE"PLUMBING"
HDL_TAP"TRUE";
"B \NAC \NWC"16;
"S \NAC"
BN"8"61;
%"TAP"
"1","(1825,2900)","0","standard","I146";
;
CDS_LIB"standard"
BODY_TYPE"PLUMBING"
HDL_TAP"TRUE";
"B \NAC \NWC"16;
"S \NAC"
BN"9"62;
%"TAP"
"1","(2000,2750)","0","standard","I147";
;
CDS_LIB"standard"
BODY_TYPE"PLUMBING"
HDL_TAP"TRUE";
"B \NAC \NWC"18;
"S \NAC"
BN"8"41;
%"TAP"
"1","(2000,2850)","0","standard","I148";
;
CDS_LIB"standard"
BODY_TYPE"PLUMBING"
HDL_TAP"TRUE";
"B \NAC \NWC"18;
"S \NAC"
BN"9"39;
%"TAP"
"1","(1825,3150)","0","standard","I149";
;
CDS_LIB"standard"
BODY_TYPE"PLUMBING"
HDL_TAP"TRUE";
"B \NAC \NWC"17;
"S \NAC"
BN"1"53;
%"TAP"
"1","(1825,3050)","0","standard","I150";
;
CDS_LIB"standard"
BODY_TYPE"PLUMBING"
HDL_TAP"TRUE";
"B \NAC \NWC"17;
"S \NAC"
BN"0"58;
%"TAP"
"1","(2000,3100)","0","standard","I151";
;
CDS_LIB"standard"
BODY_TYPE"PLUMBING"
HDL_TAP"TRUE";
"B \NAC \NWC"19;
"S \NAC"
BN"1"38;
%"TAP"
"1","(2000,3000)","0","standard","I152";
;
CDS_LIB"standard"
BODY_TYPE"PLUMBING"
HDL_TAP"TRUE";
"B \NAC \NWC"19;
"S \NAC"
BN"0"40;
%"TAP"
"1","(1825,3250)","0","standard","I153";
;
CDS_LIB"standard"
BODY_TYPE"PLUMBING"
HDL_TAP"TRUE";
"B \NAC \NWC"17;
"S \NAC"
BN"2"54;
%"TAP"
"1","(1825,3350)","0","standard","I154";
;
CDS_LIB"standard"
BODY_TYPE"PLUMBING"
HDL_TAP"TRUE";
"B \NAC \NWC"17;
"S \NAC"
BN"3"55;
%"TAP"
"1","(2000,3200)","0","standard","I155";
;
CDS_LIB"standard"
BODY_TYPE"PLUMBING"
HDL_TAP"TRUE";
"B \NAC \NWC"19;
"S \NAC"
BN"2"37;
%"TAP"
"1","(2000,3300)","0","standard","I156";
;
CDS_LIB"standard"
BODY_TYPE"PLUMBING"
HDL_TAP"TRUE";
"B \NAC \NWC"19;
"S \NAC"
BN"3"36;
%"TAP"
"1","(2000,3400)","0","standard","I157";
;
CDS_LIB"standard"
BODY_TYPE"PLUMBING"
HDL_TAP"TRUE";
"B \NAC \NWC"19;
"S \NAC"
BN"4"35;
%"TAP"
"1","(1825,3450)","0","standard","I158";
;
CDS_LIB"standard"
BODY_TYPE"PLUMBING"
HDL_TAP"TRUE";
"B \NAC \NWC"17;
"S \NAC"
BN"4"56;
%"TAP"
"1","(1825,3550)","0","standard","I159";
;
CDS_LIB"standard"
BODY_TYPE"PLUMBING"
HDL_TAP"TRUE";
"B \NAC \NWC"17;
"S \NAC"
BN"5"57;
%"TAP"
"1","(1825,3650)","0","standard","I160";
;
CDS_LIB"standard"
BODY_TYPE"PLUMBING"
HDL_TAP"TRUE";
"B \NAC \NWC"17;
"S \NAC"
BN"6"49;
%"TAP"
"1","(2000,3600)","0","standard","I161";
;
CDS_LIB"standard"
BODY_TYPE"PLUMBING"
HDL_TAP"TRUE";
"B \NAC \NWC"19;
"S \NAC"
BN"6"31;
%"TAP"
"1","(2000,3500)","0","standard","I162";
;
CDS_LIB"standard"
BODY_TYPE"PLUMBING"
HDL_TAP"TRUE";
"B \NAC \NWC"19;
"S \NAC"
BN"5"34;
%"TAP"
"1","(1825,3750)","0","standard","I166";
;
CDS_LIB"standard"
BODY_TYPE"PLUMBING"
HDL_TAP"TRUE";
"B \NAC \NWC"17;
"S \NAC"
BN"7"50;
%"TAP"
"1","(1825,3850)","0","standard","I167";
;
CDS_LIB"standard"
BODY_TYPE"PLUMBING"
HDL_TAP"TRUE";
"B \NAC \NWC"17;
"S \NAC"
BN"8"51;
%"TAP"
"1","(1825,3950)","0","standard","I168";
;
CDS_LIB"standard"
BODY_TYPE"PLUMBING"
HDL_TAP"TRUE";
"B \NAC \NWC"17;
"S \NAC"
BN"9"52;
%"TAP"
"1","(2000,3900)","0","standard","I169";
;
CDS_LIB"standard"
BODY_TYPE"PLUMBING"
HDL_TAP"TRUE";
"B \NAC \NWC"19;
"S \NAC"
BN"9"30;
%"TAP"
"1","(2000,3800)","0","standard","I170";
;
CDS_LIB"standard"
BODY_TYPE"PLUMBING"
HDL_TAP"TRUE";
"B \NAC \NWC"19;
"S \NAC"
BN"8"32;
%"TAP"
"1","(2000,3700)","0","standard","I171";
;
CDS_LIB"standard"
BODY_TYPE"PLUMBING"
HDL_TAP"TRUE";
"B \NAC \NWC"19;
"S \NAC"
BN"7"33;
%"VCC_CORE"
"1","(3500,4500)","0","logical_power","I174";
;
HDL_POWER"P12V_S3_AUX_CPU1_NVDIMM"
CDS_LIB"logical_power";
"A"3;
%"UNIVERSAL_GND"
"1","(5200,250)","0","logical_power","I176";
;
HDL_POWER"GND"
CDS_LIB"logical_power";
"A"9;
%"SCONN288_ADR50017P130CC"
"3","(4350,2325)","0","pure_quanta","I178";
;
PART_NUMBER"DFHST8FS461"
MATERIAL"IO"
PART_TYPE"SMLF"
VALUE"SCONN288_ADR50017-P130CC"
$LOCATION"J29"
NEEDS_NO_SIZE"TRUE"
CDS_LMAN_SYM_OUTLINE"-450,1775,450,-1775"
CDS_LIB"pure_quanta"
CDS_LOCATION"J29"
$SEC"3"
CDS_SEC"3";
"G3"
$PN"G3"9;
"G2"
$PN"G2"9;
"G1"
$PN"G1"9;
"VSS62"
$PN"141"9;
"VSS61"
$PN"139"9;
"VSS60"
$PN"136"9;
"VSS58"
$PN"132"9;
"VSS104"
$PN"240"8;
"VSS102"
$PN"235"8;
"VSS100"
$PN"230"8;
"VIN_BULK2"
$PN"146"3;
"VIN_BULK1"
$PN"145"3;
"VIN_BULK0"
$PN"1"3;
"VSS126"
$PN"288"8;
"VSS125"
$PN"286"8;
"VSS124"
$PN"284"8;
"VSS123"
$PN"281"8;
"VSS122"
$PN"279"8;
"VSS121"
$PN"277"8;
"VSS120"
$PN"275"8;
"VSS119"
$PN"273"8;
"VSS118"
$PN"270"8;
"VSS117"
$PN"268"8;
"VSS116"
$PN"266"8;
"VSS115"
$PN"264"8;
"VSS114"
$PN"262"8;
"VSS113"
$PN"259"8;
"VSS112"
$PN"257"8;
"VSS111"
$PN"255"8;
"VSS110"
$PN"253"8;
"VSS109"
$PN"251"8;
"VSS108"
$PN"248"8;
"VSS107"
$PN"246"8;
"VSS106"
$PN"244"8;
"VSS105"
$PN"242"8;
"VSS103"
$PN"237"8;
"VSS101"
$PN"233"8;
"VSS99"
$PN"228"8;
"VSS98"
$PN"226"8;
"VSS97"
$PN"224"8;
"VSS96"
$PN"222"8;
"VSS95"
$PN"219"8;
"VSS94"
$PN"216"8;
"VSS93"
$PN"214"8;
"VSS92"
$PN"212"8;
"VSS91"
$PN"210"8;
"VSS90"
$PN"208"8;
"VSS89"
$PN"206"8;
"VSS88"
$PN"204"8;
"VSS87"
$PN"202"8;
"VSS86"
$PN"199"8;
"VSS85"
$PN"197"8;
"VSS84"
$PN"195"8;
"VSS83"
$PN"193"8;
"VSS82"
$PN"191"8;
"VSS81"
$PN"188"8;
"VSS80"
$PN"186"8;
"VSS79"
$PN"184"8;
"VSS78"
$PN"182"8;
"VSS77"
$PN"180"8;
"VSS76"
$PN"177"8;
"VSS75"
$PN"175"8;
"VSS74"
$PN"173"8;
"VSS73"
$PN"171"8;
"VSS72"
$PN"169"8;
"VSS71"
$PN"166"8;
"VSS70"
$PN"164"8;
"VSS69"
$PN"162"8;
"VSS68"
$PN"160"8;
"VSS67"
$PN"158"8;
"VSS66"
$PN"155"8;
"VSS65"
$PN"153"8;
"VSS64"
$PN"151"8;
"VSS63"
$PN"143"9;
"VSS59"
$PN"134"9;
"VSS57"
$PN"130"9;
"VSS56"
$PN"128"9;
"VSS55"
$PN"125"9;
"VSS54"
$PN"123"9;
"VSS53"
$PN"121"9;
"VSS52"
$PN"119"9;
"VSS51"
$PN"117"9;
"VSS50"
$PN"114"9;
"VSS49"
$PN"112"9;
"VSS48"
$PN"110"9;
"VSS47"
$PN"108"9;
"VSS46"
$PN"106"9;
"VSS45"
$PN"103"9;
"VSS44"
$PN"101"9;
"VSS43"
$PN"99"9;
"VSS42"
$PN"97"9;
"VSS41"
$PN"95"9;
"VSS40"
$PN"92"9;
"VSS39"
$PN"90"9;
"VSS38"
$PN"88"9;
"VSS37"
$PN"85"9;
"VSS36"
$PN"83"9;
"VSS35"
$PN"81"9;
"VSS34"
$PN"79"9;
"VSS33"
$PN"77"9;
"VSS32"
$PN"75"9;
"VSS31"
$PN"73"9;
"VSS30"
$PN"71"9;
"VSS29"
$PN"69"9;
"VSS28"
$PN"67"9;
"VSS27"
$PN"65"9;
"VSS26"
$PN"63"9;
"VSS25"
$PN"61"9;
"VSS24"
$PN"59"9;
"VSS23"
$PN"57"9;
"VSS22"
$PN"54"9;
"VSS21"
$PN"52"9;
"VSS20"
$PN"50"9;
"VSS19"
$PN"48"9;
"VSS18"
$PN"46"9;
"VSS17"
$PN"43"9;
"VSS16"
$PN"41"9;
"VSS15"
$PN"39"9;
"VSS14"
$PN"37"9;
"VSS13"
$PN"35"9;
"VSS12"
$PN"32"9;
"VSS11"
$PN"30"9;
"VSS10"
$PN"28"9;
"VSS9"
$PN"26"9;
"VSS8"
$PN"24"9;
"VSS7"
$PN"21"9;
"VSS6"
$PN"19"9;
"VSS5"
$PN"17"9;
"VSS4"
$PN"15"9;
"VSS3"
$PN"13"9;
"VSS2"
$PN"10"9;
"VSS1"
$PN"8"9;
"VSS0"
$PN"6"9;
%"SCONN288_ADR50017P130CC"
"1","(-1750,2225)","0","pure_quanta","I179";
;
PART_NUMBER"DFHST8FS461"
MATERIAL"IO"
VALUE"SCONN288_ADR50017-P130CC"
PART_TYPE"SMLF"
$LOCATION"J29"
NEEDS_NO_SIZE"TRUE"
CDS_LMAN_SYM_OUTLINE"-450,1875,450,-1875"
CDS_LIB"pure_quanta"
CDS_LOCATION"J29"
$SEC"1"
CDS_SEC"1";
"DQ31_A"
$PN"194"177;
"CB7_A"
$PN"205"176;
"CB4_A"
$PN"58"175;
"CB1_A"
$PN"53"174;
"CB7_B"
$PN"236"173;
"ALERT_N \B"
$PN"62"22;
"CA0_A"
$PN"66"172;
"CA0_B"
$PN"76"171;
"CA1_A"
$PN"211"170;
"CA1_B"
$PN"221"169;
"CA2_A"
$PN"68"168;
"CA2_B"
$PN"78"167;
"CA3_A"
$PN"213"166;
"CA3_B"
$PN"223"165;
"CA4_A"
$PN"70"164;
"CA4_B"
$PN"80"163;
"CA5_A"
$PN"215"162;
"CA5_B"
$PN"225"161;
"CA6_A"
$PN"72"160;
"CA6_B"
$PN"82"159;
"CB6_A"
$PN"203"158;
"CB5_A"
$PN"60"157;
"CB3_A"
$PN"198"156;
"CB2_A"
$PN"196"155;
"CB0_A"
$PN"51"154;
"CB6_B"
$PN"234"69;
"CB5_B"
$PN"91"153;
"CB4_B"
$PN"89"152;
"CB3_B"
$PN"243"28;
"CB2_B"
$PN"241"151;
"CB1_B"
$PN"98"150;
"CB0_B"
$PN"96"149;
"CK_C \B"
$PN"218"148;
"CK_T"
$PN"217"147;
"CS0_A_N"
$PN"64"73;
"CS0_B_N"
$PN"84"146;
"CS1_A_N"
$PN"209"145;
"CS1_B_N"
$PN"229"144;
"DQ30_A"
$PN"192"143;
"DQ29_A"
$PN"49"142;
"DQ28_A"
$PN"47"141;
"DQ27_A"
$PN"187"140;
"DQ26_A"
$PN"185"139;
"DQ25_A"
$PN"42"138;
"DQ24_A"
$PN"40"137;
"DQ23_A"
$PN"183"136;
"DQ22_A"
$PN"181"135;
"DQ21_A"
$PN"38"134;
"DQ20_A"
$PN"36"133;
"DQ19_A"
$PN"176"132;
"DQ18_A"
$PN"174"131;
"DQ17_A"
$PN"31"130;
"DQ16_A"
$PN"29"129;
"DQ15_A"
$PN"172"128;
"DQ14_A"
$PN"170"127;
"DQ13_A"
$PN"27"126;
"DQ12_A"
$PN"25"125;
"DQ11_A"
$PN"165"124;
"DQ10_A"
$PN"163"74;
"DQ9_A"
$PN"20"123;
"DQ8_A"
$PN"18"122;
"DQ7_A"
$PN"161"121;
"DQ6_A"
$PN"159"120;
"DQ5_A"
$PN"16"119;
"DQ4_A"
$PN"14"118;
"DQ3_A"
$PN"154"117;
"DQ2_A"
$PN"152"116;
"DQ1_A"
$PN"9"115;
"DQ0_A"
$PN"7"114;
"DQ31_B"
$PN"287"113;
"DQ30_B"
$PN"285"112;
"DQ29_B"
$PN"142"111;
"DQ28_B"
$PN"140"110;
"DQ27_B"
$PN"280"109;
"DQ26_B"
$PN"278"108;
"DQ25_B"
$PN"135"75;
"DQ24_B"
$PN"133"107;
"DQ23_B"
$PN"276"106;
"DQ22_B"
$PN"274"105;
"DQ21_B"
$PN"131"104;
"DQ20_B"
$PN"129"103;
"DQ19_B"
$PN"269"102;
"DQ18_B"
$PN"267"101;
"DQ17_B"
$PN"124"100;
"DQ16_B"
$PN"122"99;
"DQ15_B"
$PN"265"98;
"DQ14_B"
$PN"263"97;
"DQ13_B"
$PN"120"96;
"DQ12_B"
$PN"118"95;
"DQ11_B"
$PN"258"94;
"DQ10_B"
$PN"256"93;
"DQ9_B"
$PN"113"92;
"DQ8_B"
$PN"111"91;
"DQ7_B"
$PN"254"90;
"DQ6_B"
$PN"252"89;
"DQ5_B"
$PN"109"88;
"DQ4_B"
$PN"107"87;
"DQ3_B"
$PN"247"86;
"DQ2_B"
$PN"245"85;
"DQ1_B"
$PN"102"84;
"DQ0_B"
$PN"100"83;
"HSA"
$PN"148"21;
"HSCL"
$PN"4"24;
"HSDA"
$PN"5"20;
"LBD||RSP_A_N"
$PN"86"82;
"LBS||RSP_B_N"
$PN"87"81;
"PAR_A"
$PN"74"80;
"PAR_B"
$PN"227"79;
"PWR_GOOD||FAIL_N"
$PN"147"26;
"RESET_N \B"
$PN"207"23;
"RFU6"
$PN"232"27;
"RFU5"
$PN"231"72;
"RFU4"
$PN"220"71;
"RFU3"
$PN"150"78;
"RFU2"
$PN"149"77;
"RFU1"
$PN"144"70;
"RFU0"
$PN"2"76;
"VIN_MGMT"
$PN"3"4;
%"SCONN288_ADR50017P130CC"
"2","(925,2950)","0","pure_quanta","I180";
;
PART_NUMBER"DFHST8FS461"
MATERIAL"IO"
VALUE"SCONN288_ADR50017-P130CC"
PART_TYPE"SMLF"
LOCATION"J29"
NEEDS_NO_SIZE"TRUE"
CDS_LMAN_SYM_OUTLINE"-600,1150,600,-1150"
CDS_LIB"pure_quanta"
$SEC"2"
CDS_SEC"2";
"DQS7_A_C||TDQS7_A_C \B"
$PN"178"33;
"DQS6_A_T||TDQS6_A_T"
$PN"168"49;
"DQS8_B_T||TDQS8_B_T"
$PN"283"61;
"DQS8_B_C||TDQS8_B_C \B"
$PN"282"41;
"DQS7_B_T||TDQS7_B_T"
$PN"272"60;
"DQS0_A_C \B"
$PN"12"40;
"DQS0_A_T"
$PN"11"58;
"DQS0_B_C \B"
$PN"105"48;
"DQS0_B_T"
$PN"104"68;
"DQS1_A_C \B"
$PN"23"38;
"DQS1_A_T"
$PN"22"53;
"DQS1_B_C \B"
$PN"116"45;
"DQS1_B_T"
$PN"115"63;
"DQS2_A_C \B"
$PN"34"37;
"DQS2_A_T"
$PN"33"54;
"DQS2_B_C \B"
$PN"127"47;
"DQS2_B_T"
$PN"126"64;
"DQS3_A_C \B"
$PN"45"36;
"DQS3_A_T"
$PN"44"55;
"DQS3_B_C \B"
$PN"138"46;
"DQS3_B_T"
$PN"137"66;
"DQS4_A_C \B"
$PN"56"35;
"DQS4_A_T"
$PN"55"56;
"DQS4_B_C \B"
$PN"238"44;
"DQS4_B_T"
$PN"239"65;
"DQS5_A_C||TDQS5_A_C||DQS5_A_T||TDQS5_A_T \B"
$PN"156"34;
"DQS5_A_T||TDQS5_A_T"
$PN"157"57;
"DQS5_B_C||TDQS5_B_C \B"
$PN"249"29;
"DQS5_B_T||TDQS5_B_T"
$PN"250"67;
"DQS6_A_C||TDQS6_A_C||DQS6_A_T||TDQS6_A_T \B"
$PN"167"31;
"DQS6_B_C||TDQS6_B_C \B"
$PN"260"43;
"DQS6_B_T||TDQS6_B_T"
$PN"261"59;
"DQS7_A_T||TDQS7_A_T"
$PN"179"50;
"DQS7_B_C||TDQS7_B_C \B"
$PN"271"42;
"DQS8_A_C||TDQS8_A_C \B"
$PN"189"32;
"DQS8_A_T||TDQS8_A_T"
$PN"190"51;
"DQS9_A_C||TDQS9_A_C \B"
$PN"200"30;
"DQS9_A_T||TDQS9_A_T"
$PN"201"52;
"DQS9_B_C||TDQS9_B_C \B"
$PN"94"39;
"DQS9_B_T||TDQS9_B_T||DBI4_B_N"
$PN"93"62;
%"Q_RES"
"1","(-3575,1250)","0","pure_quanta","I182";
;
PART_NUMBER"CS04992FB07"
MATERIAL"CHIP"
VALUE"49.9"
$LOCATION"R3903"
CDS_LIB"pure_quanta"
PACK_TYPE"0402LF"
TOLERANCE"1%"
WATTAGE"1/16W"
CDS_LOCATION"R3903"
$SEC"1"
CDS_SEC"1";
"B"
$PN"2"25;
"A"
$PN"1"24;
%"VCC_CORE"
"1","(-3400,1825)","0","logical_power","I22";
;
HDL_POWER"P3V3_AUX"
CDS_LIB"logical_power";
"A"4;
%"TAP"
"1","(-2575,1800)","2","standard","I23";
;
CDS_LIB"standard"
BODY_TYPE"PLUMBING"
HDL_TAP"TRUE";
"B \NAC \NWC"12;
"S \NAC"
BN"1"150;
%"TAP"
"1","(-2575,1850)","2","standard","I24";
;
CDS_LIB"standard"
BODY_TYPE"PLUMBING"
HDL_TAP"TRUE";
"B \NAC \NWC"12;
"S \NAC"
BN"2"151;
%"TAP"
"1","(-2575,1750)","2","standard","I25";
;
CDS_LIB"standard"
BODY_TYPE"PLUMBING"
HDL_TAP"TRUE";
"B \NAC \NWC"12;
"S \NAC"
BN"0"149;
%"TAP"
"1","(-2575,1900)","2","standard","I26";
;
CDS_LIB"standard"
BODY_TYPE"PLUMBING"
HDL_TAP"TRUE";
"B \NAC \NWC"12;
"S \NAC"
BN"3"28;
%"TAP"
"1","(-2575,1950)","2","standard","I27";
;
CDS_LIB"standard"
BODY_TYPE"PLUMBING"
HDL_TAP"TRUE";
"B \NAC \NWC"12;
"S \NAC"
BN"4"152;
%"TAP"
"1","(-2575,2000)","2","standard","I28";
;
CDS_LIB"standard"
BODY_TYPE"PLUMBING"
HDL_TAP"TRUE";
"B \NAC \NWC"12;
"S \NAC"
BN"5"153;
%"TAP"
"1","(-2575,2050)","2","standard","I29";
;
CDS_LIB"standard"
BODY_TYPE"PLUMBING"
HDL_TAP"TRUE";
"B \NAC \NWC"12;
"S \NAC"
BN"6"69;
%"TAP"
"1","(-2575,2100)","2","standard","I30";
;
CDS_LIB"standard"
BODY_TYPE"PLUMBING"
HDL_TAP"TRUE";
"B \NAC \NWC"12;
"S \NAC"
BN"7"173;
%"TAP"
"1","(-2575,2300)","2","standard","I31";
;
CDS_LIB"standard"
BODY_TYPE"PLUMBING"
HDL_TAP"TRUE";
"B \NAC \NWC"11;
"S \NAC"
BN"2"155;
%"TAP"
"1","(-2575,2350)","2","standard","I32";
;
CDS_LIB"standard"
BODY_TYPE"PLUMBING"
HDL_TAP"TRUE";
"B \NAC \NWC"11;
"S \NAC"
BN"3"156;
%"TAP"
"1","(-2575,2250)","2","standard","I33";
;
CDS_LIB"standard"
BODY_TYPE"PLUMBING"
HDL_TAP"TRUE";
"B \NAC \NWC"11;
"S \NAC"
BN"1"174;
%"TAP"
"1","(-2575,2200)","2","standard","I34";
;
CDS_LIB"standard"
BODY_TYPE"PLUMBING"
HDL_TAP"TRUE";
"B \NAC \NWC"11;
"S \NAC"
BN"0"154;
%"TAP"
"1","(-2575,2400)","2","standard","I35";
;
CDS_LIB"standard"
BODY_TYPE"PLUMBING"
HDL_TAP"TRUE";
"B \NAC \NWC"11;
"S \NAC"
BN"4"175;
%"TAP"
"1","(-2575,2550)","2","standard","I36";
;
CDS_LIB"standard"
BODY_TYPE"PLUMBING"
HDL_TAP"TRUE";
"B \NAC \NWC"11;
"S \NAC"
BN"7"176;
%"TAP"
"1","(-2575,2500)","2","standard","I37";
;
CDS_LIB"standard"
BODY_TYPE"PLUMBING"
HDL_TAP"TRUE";
"B \NAC \NWC"11;
"S \NAC"
BN"6"158;
%"TAP"
"1","(-2575,2450)","2","standard","I38";
;
CDS_LIB"standard"
BODY_TYPE"PLUMBING"
HDL_TAP"TRUE";
"B \NAC \NWC"11;
"S \NAC"
BN"5"157;
%"TAP"
"1","(-2575,3300)","2","standard","I39";
;
CDS_LIB"standard"
BODY_TYPE"PLUMBING"
HDL_TAP"TRUE";
"B \NAC \NWC"14;
"S \NAC"
BN"1"169;
%"TAP"
"1","(-2575,3350)","2","standard","I40";
;
CDS_LIB"standard"
BODY_TYPE"PLUMBING"
HDL_TAP"TRUE";
"B \NAC \NWC"14;
"S \NAC"
BN"2"167;
%"TAP"
"1","(-2575,3400)","2","standard","I41";
;
CDS_LIB"standard"
BODY_TYPE"PLUMBING"
HDL_TAP"TRUE";
"B \NAC \NWC"14;
"S \NAC"
BN"3"165;
%"TAP"
"1","(-2575,3250)","2","standard","I42";
;
CDS_LIB"standard"
BODY_TYPE"PLUMBING"
HDL_TAP"TRUE";
"B \NAC \NWC"14;
"S \NAC"
BN"0"171;
%"TAP"
"1","(-2575,3450)","2","standard","I43";
;
CDS_LIB"standard"
BODY_TYPE"PLUMBING"
HDL_TAP"TRUE";
"B \NAC \NWC"14;
"S \NAC"
BN"4"163;
%"TAP"
"1","(-2575,3500)","2","standard","I44";
;
CDS_LIB"standard"
BODY_TYPE"PLUMBING"
HDL_TAP"TRUE";
"B \NAC \NWC"14;
"S \NAC"
BN"5"161;
%"TAP"
"1","(-2575,3550)","2","standard","I45";
;
CDS_LIB"standard"
BODY_TYPE"PLUMBING"
HDL_TAP"TRUE";
"B \NAC \NWC"14;
"S \NAC"
BN"6"159;
%"TAP"
"1","(-2575,3650)","2","standard","I46";
;
CDS_LIB"standard"
BODY_TYPE"PLUMBING"
HDL_TAP"TRUE";
"B \NAC \NWC"13;
"S \NAC"
BN"0"172;
%"Q_RES"
"2","(-2350,-200)","0","pure_quanta","I47";
;
PART_NUMBER"CS35492FB03"
VALUE"54.9K"
WATTAGE"1/16W"
MATERIAL"CHIP"
TOLERANCE"1%"
PACK_TYPE"0402LF"
$LOCATION"R75"
CDS_LIB"pure_quanta"
$LOCATION"R75"
CDS_LOCATION"R75"
$SEC"1"
CDS_SEC"1";
"A"
$PN"1"178;
"B"
$PN"2"5;
%"TAP"
"1","(-925,750)","0","standard","I48";
;
CDS_LIB"standard"
BODY_TYPE"PLUMBING"
HDL_TAP"TRUE";
"B \NAC \NWC"15;
"S \NAC"
BN"0"83;
%"TAP"
"1","(-925,850)","0","standard","I49";
;
CDS_LIB"standard"
BODY_TYPE"PLUMBING"
HDL_TAP"TRUE";
"B \NAC \NWC"15;
"S \NAC"
BN"2"85;
%"TAP"
"1","(-925,800)","0","standard","I50";
;
CDS_LIB"standard"
BODY_TYPE"PLUMBING"
HDL_TAP"TRUE";
"B \NAC \NWC"15;
"S \NAC"
BN"1"84;
%"TAP"
"1","(-925,900)","0","standard","I51";
;
CDS_LIB"standard"
BODY_TYPE"PLUMBING"
HDL_TAP"TRUE";
"B \NAC \NWC"15;
"S \NAC"
BN"3"86;
%"TAP"
"1","(-925,950)","0","standard","I52";
;
CDS_LIB"standard"
BODY_TYPE"PLUMBING"
HDL_TAP"TRUE";
"B \NAC \NWC"15;
"S \NAC"
BN"4"87;
%"TAP"
"1","(-925,1000)","0","standard","I53";
;
CDS_LIB"standard"
BODY_TYPE"PLUMBING"
HDL_TAP"TRUE";
"B \NAC \NWC"15;
"S \NAC"
BN"5"88;
%"TAP"
"1","(-925,1100)","0","standard","I54";
;
CDS_LIB"standard"
BODY_TYPE"PLUMBING"
HDL_TAP"TRUE";
"B \NAC \NWC"15;
"S \NAC"
BN"7"90;
%"TAP"
"1","(-925,1050)","0","standard","I55";
;
CDS_LIB"standard"
BODY_TYPE"PLUMBING"
HDL_TAP"TRUE";
"B \NAC \NWC"15;
"S \NAC"
BN"6"89;
%"TAP"
"1","(-925,1150)","0","standard","I56";
;
CDS_LIB"standard"
BODY_TYPE"PLUMBING"
HDL_TAP"TRUE";
"B \NAC \NWC"15;
"S \NAC"
BN"8"91;
%"TAP"
"1","(-925,1200)","0","standard","I57";
;
CDS_LIB"standard"
BODY_TYPE"PLUMBING"
HDL_TAP"TRUE";
"B \NAC \NWC"15;
"S \NAC"
BN"9"92;
%"TAP"
"1","(-925,1250)","0","standard","I58";
;
CDS_LIB"standard"
BODY_TYPE"PLUMBING"
HDL_TAP"TRUE";
"B \NAC \NWC"15;
"S \NAC"
BN"10"93;
%"TAP"
"1","(-925,1300)","0","standard","I59";
;
CDS_LIB"standard"
BODY_TYPE"PLUMBING"
HDL_TAP"TRUE";
"B \NAC \NWC"15;
"S \NAC"
BN"11"94;
%"TAP"
"1","(-925,1350)","0","standard","I60";
;
CDS_LIB"standard"
BODY_TYPE"PLUMBING"
HDL_TAP"TRUE";
"B \NAC \NWC"15;
"S \NAC"
BN"12"95;
%"TAP"
"1","(-925,1400)","0","standard","I61";
;
CDS_LIB"standard"
BODY_TYPE"PLUMBING"
HDL_TAP"TRUE";
"B \NAC \NWC"15;
"S \NAC"
BN"13"96;
%"TAP"
"1","(-925,1450)","0","standard","I62";
;
CDS_LIB"standard"
BODY_TYPE"PLUMBING"
HDL_TAP"TRUE";
"B \NAC \NWC"15;
"S \NAC"
BN"14"97;
%"TAP"
"1","(-925,1500)","0","standard","I63";
;
CDS_LIB"standard"
BODY_TYPE"PLUMBING"
HDL_TAP"TRUE";
"B \NAC \NWC"15;
"S \NAC"
BN"15"98;
%"TAP"
"1","(-925,1550)","0","standard","I64";
;
CDS_LIB"standard"
BODY_TYPE"PLUMBING"
HDL_TAP"TRUE";
"B \NAC \NWC"15;
"S \NAC"
BN"16"99;
%"TAP"
"1","(-925,1600)","0","standard","I65";
;
CDS_LIB"standard"
BODY_TYPE"PLUMBING"
HDL_TAP"TRUE";
"B \NAC \NWC"15;
"S \NAC"
BN"17"100;
%"TAP"
"1","(-925,1650)","0","standard","I66";
;
CDS_LIB"standard"
BODY_TYPE"PLUMBING"
HDL_TAP"TRUE";
"B \NAC \NWC"15;
"S \NAC"
BN"18"101;
%"TAP"
"1","(-925,1700)","0","standard","I67";
;
CDS_LIB"standard"
BODY_TYPE"PLUMBING"
HDL_TAP"TRUE";
"B \NAC \NWC"15;
"S \NAC"
BN"19"102;
%"TAP"
"1","(-925,1750)","0","standard","I68";
;
CDS_LIB"standard"
BODY_TYPE"PLUMBING"
HDL_TAP"TRUE";
"B \NAC \NWC"15;
"S \NAC"
BN"20"103;
%"TAP"
"1","(-925,1800)","0","standard","I69";
;
CDS_LIB"standard"
BODY_TYPE"PLUMBING"
HDL_TAP"TRUE";
"B \NAC \NWC"15;
"S \NAC"
BN"21"104;
%"TAP"
"1","(-925,1900)","0","standard","I70";
;
CDS_LIB"standard"
BODY_TYPE"PLUMBING"
HDL_TAP"TRUE";
"B \NAC \NWC"15;
"S \NAC"
BN"23"106;
%"TAP"
"1","(-925,1850)","0","standard","I71";
;
CDS_LIB"standard"
BODY_TYPE"PLUMBING"
HDL_TAP"TRUE";
"B \NAC \NWC"15;
"S \NAC"
BN"22"105;
%"TAP"
"1","(-925,1950)","0","standard","I72";
;
CDS_LIB"standard"
BODY_TYPE"PLUMBING"
HDL_TAP"TRUE";
"B \NAC \NWC"15;
"S \NAC"
BN"24"107;
%"TAP"
"1","(-925,2000)","0","standard","I73";
;
CDS_LIB"standard"
BODY_TYPE"PLUMBING"
HDL_TAP"TRUE";
"B \NAC \NWC"15;
"S \NAC"
BN"25"75;
%"TAP"
"1","(-925,2050)","0","standard","I74";
;
CDS_LIB"standard"
BODY_TYPE"PLUMBING"
HDL_TAP"TRUE";
"B \NAC \NWC"15;
"S \NAC"
BN"26"108;
%"TAP"
"1","(-925,2150)","0","standard","I75";
;
CDS_LIB"standard"
BODY_TYPE"PLUMBING"
HDL_TAP"TRUE";
"B \NAC \NWC"15;
"S \NAC"
BN"28"110;
%"TAP"
"1","(-925,2100)","0","standard","I76";
;
CDS_LIB"standard"
BODY_TYPE"PLUMBING"
HDL_TAP"TRUE";
"B \NAC \NWC"15;
"S \NAC"
BN"27"109;
%"TAP"
"1","(-925,2200)","0","standard","I77";
;
CDS_LIB"standard"
BODY_TYPE"PLUMBING"
HDL_TAP"TRUE";
"B \NAC \NWC"15;
"S \NAC"
BN"29"111;
%"TAP"
"1","(-925,2250)","0","standard","I78";
;
CDS_LIB"standard"
BODY_TYPE"PLUMBING"
HDL_TAP"TRUE";
"B \NAC \NWC"15;
"S \NAC"
BN"30"112;
%"TAP"
"1","(-925,2400)","0","standard","I79";
;
CDS_LIB"standard"
BODY_TYPE"PLUMBING"
HDL_TAP"TRUE";
"B \NAC \NWC"10;
"S \NAC"
BN"0"114;
%"TAP"
"1","(-925,2300)","0","standard","I80";
;
CDS_LIB"standard"
BODY_TYPE"PLUMBING"
HDL_TAP"TRUE";
"B \NAC \NWC"15;
"S \NAC"
BN"31"113;
%"TAP"
"1","(-925,2500)","0","standard","I81";
;
CDS_LIB"standard"
BODY_TYPE"PLUMBING"
HDL_TAP"TRUE";
"B \NAC \NWC"10;
"S \NAC"
BN"2"116;
%"TAP"
"1","(-925,2450)","0","standard","I82";
;
CDS_LIB"standard"
BODY_TYPE"PLUMBING"
HDL_TAP"TRUE";
"B \NAC \NWC"10;
"S \NAC"
BN"1"115;
%"TAP"
"1","(-925,2600)","0","standard","I83";
;
CDS_LIB"standard"
BODY_TYPE"PLUMBING"
HDL_TAP"TRUE";
"B \NAC \NWC"10;
"S \NAC"
BN"4"118;
%"TAP"
"1","(-925,2550)","0","standard","I84";
;
CDS_LIB"standard"
BODY_TYPE"PLUMBING"
HDL_TAP"TRUE";
"B \NAC \NWC"10;
"S \NAC"
BN"3"117;
%"TAP"
"1","(-925,2650)","0","standard","I85";
;
CDS_LIB"standard"
BODY_TYPE"PLUMBING"
HDL_TAP"TRUE";
"B \NAC \NWC"10;
"S \NAC"
BN"5"119;
%"TAP"
"1","(-925,2750)","0","standard","I86";
;
CDS_LIB"standard"
BODY_TYPE"PLUMBING"
HDL_TAP"TRUE";
"B \NAC \NWC"10;
"S \NAC"
BN"7"121;
%"TAP"
"1","(-925,2700)","0","standard","I87";
;
CDS_LIB"standard"
BODY_TYPE"PLUMBING"
HDL_TAP"TRUE";
"B \NAC \NWC"10;
"S \NAC"
BN"6"120;
%"TAP"
"1","(-925,2800)","0","standard","I88";
;
CDS_LIB"standard"
BODY_TYPE"PLUMBING"
HDL_TAP"TRUE";
"B \NAC \NWC"10;
"S \NAC"
BN"8"122;
%"TAP"
"1","(-925,2900)","0","standard","I89";
;
CDS_LIB"standard"
BODY_TYPE"PLUMBING"
HDL_TAP"TRUE";
"B \NAC \NWC"10;
"S \NAC"
BN"10"74;
%"TAP"
"1","(-925,2850)","0","standard","I90";
;
CDS_LIB"standard"
BODY_TYPE"PLUMBING"
HDL_TAP"TRUE";
"B \NAC \NWC"10;
"S \NAC"
BN"9"123;
%"TAP"
"1","(-925,2950)","0","standard","I91";
;
CDS_LIB"standard"
BODY_TYPE"PLUMBING"
HDL_TAP"TRUE";
"B \NAC \NWC"10;
"S \NAC"
BN"11"124;
%"TAP"
"1","(-925,3050)","0","standard","I92";
;
CDS_LIB"standard"
BODY_TYPE"PLUMBING"
HDL_TAP"TRUE";
"B \NAC \NWC"10;
"S \NAC"
BN"13"126;
%"TAP"
"1","(-925,3000)","0","standard","I93";
;
CDS_LIB"standard"
BODY_TYPE"PLUMBING"
HDL_TAP"TRUE";
"B \NAC \NWC"10;
"S \NAC"
BN"12"125;
%"TAP"
"1","(-925,3150)","0","standard","I94";
;
CDS_LIB"standard"
BODY_TYPE"PLUMBING"
HDL_TAP"TRUE";
"B \NAC \NWC"10;
"S \NAC"
BN"15"128;
%"TAP"
"1","(-925,3100)","0","standard","I95";
;
CDS_LIB"standard"
BODY_TYPE"PLUMBING"
HDL_TAP"TRUE";
"B \NAC \NWC"10;
"S \NAC"
BN"14"127;
%"TAP"
"1","(-925,3200)","0","standard","I96";
;
CDS_LIB"standard"
BODY_TYPE"PLUMBING"
HDL_TAP"TRUE";
"B \NAC \NWC"10;
"S \NAC"
BN"16"129;
%"TAP"
"1","(-925,3300)","0","standard","I97";
;
CDS_LIB"standard"
BODY_TYPE"PLUMBING"
HDL_TAP"TRUE";
"B \NAC \NWC"10;
"S \NAC"
BN"18"131;
%"TAP"
"1","(-925,3250)","0","standard","I98";
;
CDS_LIB"standard"
BODY_TYPE"PLUMBING"
HDL_TAP"TRUE";
"B \NAC \NWC"10;
"S \NAC"
BN"17"130;
%"TAP"
"1","(-925,3350)","0","standard","I99";
;
CDS_LIB"standard"
BODY_TYPE"PLUMBING"
HDL_TAP"TRUE";
"B \NAC \NWC"10;
"S \NAC"
BN"19"132;
END.
